(kicad_pcb
	(version 20260206)
	(generator "pcbnew")
	(generator_version "10.0")
	(general
		(thickness 1.6)
		(legacy_teardrops no)
	)
	(paper "A4")
	(title_block
		(title "Bryce Canyon_F.DPB_16315-1-OCP.brd")
		(comment 1 "Bryce Canyon / footprints 822-828 of 2223")
	)
	(layers
		(0 "F.Cu" signal "TOP")
		(4 "In1.Cu" signal "L2GND")
		(6 "In2.Cu" signal "L3")
		(8 "In3.Cu" signal "L4GND")
		(10 "In4.Cu" signal "L5")
		(12 "In5.Cu" signal "L6VCC")
		(14 "In6.Cu" signal "L7VCC")
		(16 "In7.Cu" signal "L8")
		(18 "In8.Cu" signal "L9GND")
		(20 "In9.Cu" signal "L10")
		(22 "In10.Cu" signal "L11GND")
		(2 "B.Cu" signal "BOTTOM")
		(9 "F.Adhes" user "F.Adhesive")
		(11 "B.Adhes" user "B.Adhesive")
		(13 "F.Paste" user "Package Geometry/Pastemask Top")
		(15 "B.Paste" user "Package Geometry/Pastemask Bottom")
		(5 "F.SilkS" user "Ref Des/Silkscreen Top")
		(7 "B.SilkS" user "Ref Des/Silkscreen Bottom")
		(1 "F.Mask" user "Board Geometry/Soldermask Top")
		(3 "B.Mask" user "Board Geometry/Soldermask Bottom")
		(17 "Dwgs.User" user "User.Drawings")
		(19 "Cmts.User" user "User.Comments")
		(21 "Eco1.User" user "User.Eco1")
		(23 "Eco2.User" user "User.Eco2")
		(25 "Edge.Cuts" user "Board Geometry/Outline")
		(27 "Margin" user)
		(31 "F.CrtYd" user "Package Geometry/Place Bound Top")
		(29 "B.CrtYd" user "Package Geometry/Place Bound Bottom")
		(35 "F.Fab" user "Ref Des/Assembly Top")
		(33 "B.Fab" user "Ref Des/Assembly Bottom")
	)
	(footprint ""
		(layer "F.Cu")
		(at 77.822552 -127.78867 180)
		(property "Reference" "Q241"
			(at 0 0 180)
			(layer "F.SilkS")
			(hide yes)
			(effects
				(font
					(size 1.27 1.27)
				)
			)
		)
		(property "Value" "2N7002K-2-GP"
			(at 0.127 -8.9662 180)
			(unlocked yes)
			(layer "F.Fab")
			(hide yes)
			(effects
				(font
					(size 1.016 1.016)
					(thickness 0.1524)
				)
			)
		)
		(property "Device Type" "SOT23DGS2D4H44"
			(at 0.127 -10.4902 180)
			(unlocked yes)
			(layer "F.Fab")
			(hide yes)
			(effects
				(font
					(size 1.016 1.016)
					(thickness 0.1524)
				)
			)
		)
		(duplicate_pad_numbers_are_jumpers no)
		(fp_line
			(start 1.651 1.778)
			(end 1.651 -1.778)
			(stroke
				(width 0.1524)
				(type default)
			)
			(layer "F.SilkS")
		)
		(fp_line
			(start 1.651 -1.778)
			(end -1.651 -1.778)
			(stroke
				(width 0.1524)
				(type default)
			)
			(layer "F.SilkS")
		)
		(fp_line
			(start -1.651 1.778)
			(end 1.651 1.778)
			(stroke
				(width 0.1524)
				(type default)
			)
			(layer "F.SilkS")
		)
		(fp_line
			(start -1.651 -1.778)
			(end -1.651 1.778)
			(stroke
				(width 0.1524)
				(type default)
			)
			(layer "F.SilkS")
		)
		(fp_poly
			(pts
				(xy -1.778 1.8796) (xy -1.778 -1.8796) (xy 1.778 -1.8796) (xy 1.778 1.8796)
			)
			(stroke
				(width 0)
				(type default)
			)
			(fill no)
			(layer "F.CrtYd")
		)
		(fp_poly
			(pts
				(xy -1.778 1.8796) (xy -1.778 -1.8796) (xy 1.778 -1.8796) (xy 1.778 1.8796)
			)
			(stroke
				(width 0)
				(type default)
			)
			(fill no)
			(layer "F.Fab")
		)
		(pad "D" smd custom
			(at 0 -0.9525 180)
			(size 0.1905 0.1905)
			(layers "F.Cu" "F.Mask" "F.Paste")
			(net "FLT_HDD14_N")
			(options
				(clearance outline)
				(anchor circle)
			)
			(primitives
				(gr_poly
					(pts
						(arc
							(start -0.1778 0.5715)
							(mid -0.321484 0.511984)
							(end -0.381 0.3683)
						)
						(arc
							(start -0.381 -0.3683)
							(mid -0.321484 -0.511984)
							(end -0.1778 -0.5715)
						)
						(arc
							(start 0.1778 -0.5715)
							(mid 0.321484 -0.511984)
							(end 0.381 -0.3683)
						)
						(arc
							(start 0.381 0.3683)
							(mid 0.321484 0.511984)
							(end 0.1778 0.5715)
						)
					)
					(width 0)
					(fill yes)
				)
			)
		)
		(pad "G" smd custom
			(at -0.98425 0.9525 180)
			(size 0.1905 0.1905)
			(layers "F.Cu" "F.Mask" "F.Paste")
			(net "DRIVE_A_14_FLT_LED")
			(options
				(clearance outline)
				(anchor circle)
			)
			(primitives
				(gr_poly
					(pts
						(arc
							(start -0.1778 0.5715)
							(mid -0.321484 0.511984)
							(end -0.381 0.3683)
						)
						(arc
							(start -0.381 -0.3683)
							(mid -0.321484 -0.511984)
							(end -0.1778 -0.5715)
						)
						(arc
							(start 0.1778 -0.5715)
							(mid 0.321484 -0.511984)
							(end 0.381 -0.3683)
						)
						(arc
							(start 0.381 0.3683)
							(mid 0.321484 0.511984)
							(end 0.1778 0.5715)
						)
					)
					(width 0)
					(fill yes)
				)
			)
		)
		(pad "S" smd custom
			(at 0.98425 0.9525 180)
			(size 0.1905 0.1905)
			(layers "F.Cu" "F.Mask" "F.Paste")
			(net "GND")
			(options
				(clearance outline)
				(anchor circle)
			)
			(primitives
				(gr_poly
					(pts
						(arc
							(start -0.1778 0.5715)
							(mid -0.321484 0.511984)
							(end -0.381 0.3683)
						)
						(arc
							(start -0.381 -0.3683)
							(mid -0.321484 -0.511984)
							(end -0.1778 -0.5715)
						)
						(arc
							(start 0.1778 -0.5715)
							(mid 0.321484 -0.511984)
							(end 0.381 -0.3683)
						)
						(arc
							(start 0.381 0.3683)
							(mid 0.321484 0.511984)
							(end 0.1778 0.5715)
						)
					)
					(width 0)
					(fill yes)
				)
			)
		)
	)
	(footprint ""
		(layer "F.Cu")
		(at 440.144662 -287.44799)
		(property "Reference" "Q297"
			(at 0 0 0)
			(layer "F.SilkS")
			(hide yes)
			(effects
				(font
					(size 1.27 1.27)
				)
			)
		)
		(property "Value" "SSM3K324R-GP"
			(at 0.127 -8.9662 0)
			(unlocked yes)
			(layer "F.Fab")
			(hide yes)
			(effects
				(font
					(size 1.016 1.016)
					(thickness 0.1524)
				)
			)
		)
		(property "Device Type" "SOT23DGS2D4H35"
			(at 0.127 -10.4902 0)
			(unlocked yes)
			(layer "F.Fab")
			(hide yes)
			(effects
				(font
					(size 1.016 1.016)
					(thickness 0.1524)
				)
			)
		)
		(duplicate_pad_numbers_are_jumpers no)
		(fp_line
			(start -1.651 -1.778)
			(end -1.651 1.778)
			(stroke
				(width 0.1524)
				(type default)
			)
			(layer "F.SilkS")
		)
		(fp_line
			(start -1.651 1.778)
			(end 1.651 1.778)
			(stroke
				(width 0.1524)
				(type default)
			)
			(layer "F.SilkS")
		)
		(fp_line
			(start 1.651 -1.778)
			(end -1.651 -1.778)
			(stroke
				(width 0.1524)
				(type default)
			)
			(layer "F.SilkS")
		)
		(fp_line
			(start 1.651 1.778)
			(end 1.651 -1.778)
			(stroke
				(width 0.1524)
				(type default)
			)
			(layer "F.SilkS")
		)
		(fp_poly
			(pts
				(xy -1.778 1.8796) (xy -1.778 -1.8796) (xy 1.778 -1.8796) (xy 1.778 1.8796)
			)
			(stroke
				(width 0)
				(type default)
			)
			(fill no)
			(layer "F.CrtYd")
		)
		(fp_poly
			(pts
				(xy -1.778 1.8796) (xy -1.778 -1.8796) (xy 1.778 -1.8796) (xy 1.778 1.8796)
			)
			(stroke
				(width 0)
				(type default)
			)
			(fill no)
			(layer "F.Fab")
		)
		(pad "D" smd custom
			(at 0 -0.9525)
			(size 0.1905 0.1905)
			(layers "F.Cu" "F.Mask" "F.Paste")
			(net "DRV_ACT_34_N")
			(options
				(clearance outline)
				(anchor circle)
			)
			(primitives
				(gr_poly
					(pts
						(arc
							(start -0.1778 0.5715)
							(mid -0.321484 0.511984)
							(end -0.381 0.3683)
						)
						(arc
							(start -0.381 -0.3683)
							(mid -0.321484 -0.511984)
							(end -0.1778 -0.5715)
						)
						(arc
							(start 0.1778 -0.5715)
							(mid 0.321484 -0.511984)
							(end 0.381 -0.3683)
						)
						(arc
							(start 0.381 0.3683)
							(mid 0.321484 0.511984)
							(end 0.1778 0.5715)
						)
					)
					(width 0)
					(fill yes)
				)
			)
		)
		(pad "G" smd custom
			(at -0.98425 0.9525)
			(size 0.1905 0.1905)
			(layers "F.Cu" "F.Mask" "F.Paste")
			(net "DRIVE_B_34_ACT")
			(options
				(clearance outline)
				(anchor circle)
			)
			(primitives
				(gr_poly
					(pts
						(arc
							(start -0.1778 0.5715)
							(mid -0.321484 0.511984)
							(end -0.381 0.3683)
						)
						(arc
							(start -0.381 -0.3683)
							(mid -0.321484 -0.511984)
							(end -0.1778 -0.5715)
						)
						(arc
							(start 0.1778 -0.5715)
							(mid 0.321484 -0.511984)
							(end 0.381 -0.3683)
						)
						(arc
							(start 0.381 0.3683)
							(mid 0.321484 0.511984)
							(end 0.1778 0.5715)
						)
					)
					(width 0)
					(fill yes)
				)
			)
		)
		(pad "S" smd custom
			(at 0.98425 0.9525)
			(size 0.1905 0.1905)
			(layers "F.Cu" "F.Mask" "F.Paste")
			(net "GND")
			(options
				(clearance outline)
				(anchor circle)
			)
			(primitives
				(gr_poly
					(pts
						(arc
							(start -0.1778 0.5715)
							(mid -0.321484 0.511984)
							(end -0.381 0.3683)
						)
						(arc
							(start -0.381 -0.3683)
							(mid -0.321484 -0.511984)
							(end -0.1778 -0.5715)
						)
						(arc
							(start 0.1778 -0.5715)
							(mid 0.321484 -0.511984)
							(end 0.381 -0.3683)
						)
						(arc
							(start 0.381 0.3683)
							(mid 0.321484 0.511984)
							(end 0.1778 0.5715)
						)
					)
					(width 0)
					(fill yes)
				)
			)
		)
	)
	(footprint ""
		(layer "F.Cu")
		(at 150.440898 -189.462918 180)
		(property "Reference" "C255"
			(at 0 0 180)
			(layer "F.SilkS")
			(hide yes)
			(effects
				(font
					(size 1.27 1.27)
				)
			)
		)
		(property "Value" "SC1U25V3KX-GP"
			(at 0 -2.8194 180)
			(unlocked yes)
			(layer "F.Fab")
			(hide yes)
			(effects
				(font
					(size 1.016 1.016)
					(thickness 0.1524)
				)
			)
		)
		(property "Device Type" "C603H36"
			(at 0 -4.3434 180)
			(unlocked yes)
			(layer "F.Fab")
			(hide yes)
			(effects
				(font
					(size 1.016 1.016)
					(thickness 0.1524)
				)
			)
		)
		(duplicate_pad_numbers_are_jumpers no)
		(fp_line
			(start 0.508 0)
			(end -0.508 0)
			(stroke
				(width 0.2032)
				(type default)
			)
			(layer "F.SilkS")
		)
		(fp_rect
			(start -0.5842 1.3335)
			(end 0.5842 -1.3335)
			(stroke
				(width 0)
				(type default)
			)
			(fill no)
			(layer "F.CrtYd")
		)
		(fp_rect
			(start -0.5842 1.3335)
			(end 0.5842 -1.3335)
			(stroke
				(width 0)
				(type default)
			)
			(fill no)
			(layer "F.Fab")
		)
		(pad "1" smd custom
			(at 0 -0.762 180)
			(size 0.2159 0.2159)
			(layers "F.Cu" "F.Mask" "F.Paste")
			(net "P12V_HDD16")
			(options
				(clearance outline)
				(anchor circle)
			)
			(primitives
				(gr_poly
					(pts
						(arc
							(start -0.3302 -0.4318)
							(mid -0.402042 -0.402042)
							(end -0.4318 -0.3302)
						)
						(arc
							(start -0.4318 0.3302)
							(mid -0.402042 0.402042)
							(end -0.3302 0.4318)
						)
						(arc
							(start 0.3302 0.4318)
							(mid 0.402042 0.402042)
							(end 0.4318 0.3302)
						)
						(arc
							(start 0.4318 -0.3302)
							(mid 0.402042 -0.402042)
							(end 0.3302 -0.4318)
						)
					)
					(width 0)
					(fill yes)
				)
			)
		)
		(pad "2" smd custom
			(at 0 0.762 180)
			(size 0.2159 0.2159)
			(layers "F.Cu" "F.Mask" "F.Paste")
			(net "GND")
			(options
				(clearance outline)
				(anchor circle)
			)
			(primitives
				(gr_poly
					(pts
						(arc
							(start -0.3302 -0.4318)
							(mid -0.402042 -0.402042)
							(end -0.4318 -0.3302)
						)
						(arc
							(start -0.4318 0.3302)
							(mid -0.402042 0.402042)
							(end -0.3302 0.4318)
						)
						(arc
							(start 0.3302 0.4318)
							(mid 0.402042 0.402042)
							(end 0.4318 0.3302)
						)
						(arc
							(start 0.4318 -0.3302)
							(mid 0.402042 -0.402042)
							(end 0.3302 -0.4318)
						)
					)
					(width 0)
					(fill yes)
				)
			)
		)
	)
	(footprint ""
		(layer "F.Cu")
		(at 272.542 -316.30493 180)
		(property "Reference" "VIA57"
			(at 0 0 180)
			(layer "F.SilkS")
			(hide yes)
			(effects
				(font
					(size 1.27 1.27)
				)
			)
		)
		(property "Value" "100OHM-8L-1D6MM-L18L16-GP"
			(at -3.7211 -4.5085 180)
			(unlocked yes)
			(layer "F.Fab")
			(hide yes)
			(effects
				(font
					(size 1.016 1.016)
					(thickness 0.1524)
				)
			)
		)
		(property "Device Type" "VIA-PCIE-4P-394076"
			(at -3.7211 -6.0325 180)
			(unlocked yes)
			(layer "F.Fab")
			(hide yes)
			(effects
				(font
					(size 1.016 1.016)
					(thickness 0.1524)
				)
			)
		)
		(duplicate_pad_numbers_are_jumpers no)
		(fp_rect
			(start -1.9685 0.381)
			(end 1.9685 -0.381)
			(stroke
				(width 0)
				(type default)
			)
			(fill no)
			(layer "F.CrtYd")
		)
		(fp_rect
			(start -1.9685 0.381)
			(end 1.9685 -0.381)
			(stroke
				(width 0)
				(type default)
			)
			(fill no)
			(layer "F.Fab")
		)
		(pad "1" thru_hole circle
			(at -1.5875 0 180)
			(size 0.508 0.508)
			(drill 0.254)
			(layers "*.Cu" "*.Mask")
			(remove_unused_layers no)
			(net "GND")
			(clearance 0.127)
			(thermal_gap 0.127)
		)
		(pad "2" thru_hole circle
			(at -0.5715 0 180)
			(size 0.508 0.508)
			(drill 0.254)
			(layers "*.Cu" "*.Mask")
			(remove_unused_layers no)
			(net "PHY_SCC_A_TO_DRV_A_24_DP")
			(clearance 0.127)
			(thermal_gap 0.127)
		)
		(pad "3" thru_hole circle
			(at 0.5715 0 180)
			(size 0.508 0.508)
			(drill 0.254)
			(layers "*.Cu" "*.Mask")
			(remove_unused_layers no)
			(net "PHY_SCC_A_TO_DRV_A_24_DN")
			(clearance 0.127)
			(thermal_gap 0.127)
		)
		(pad "4" thru_hole circle
			(at 1.5875 0 180)
			(size 0.508 0.508)
			(drill 0.254)
			(layers "*.Cu" "*.Mask")
			(remove_unused_layers no)
			(net "GND")
			(clearance 0.127)
			(thermal_gap 0.127)
		)
	)
	(footprint ""
		(layer "F.Cu")
		(at 479.036126 -71.287894)
		(property "Reference" "C500"
			(at 0 0 0)
			(layer "F.SilkS")
			(hide yes)
			(effects
				(font
					(size 1.27 1.27)
				)
			)
		)
		(property "Value" "SC4D7U25V5KX-1-GP"
			(at -0.0762 -6.1214 0)
			(unlocked yes)
			(layer "F.Fab")
			(hide yes)
			(effects
				(font
					(size 1.016 1.016)
					(thickness 0.1524)
				)
			)
		)
		(property "Device Type" "C805H58"
			(at -0.0762 -8.1534 0)
			(unlocked yes)
			(layer "F.Fab")
			(hide yes)
			(effects
				(font
					(size 1.016 1.016)
					(thickness 0.1524)
				)
			)
		)
		(duplicate_pad_numbers_are_jumpers no)
		(fp_line
			(start 0.635 0)
			(end -0.635 0)
			(stroke
				(width 0.508)
				(type default)
			)
			(layer "F.SilkS")
		)
		(fp_rect
			(start -0.9652 1.778)
			(end 0.9652 -1.778)
			(stroke
				(width 0)
				(type default)
			)
			(fill no)
			(layer "F.CrtYd")
		)
		(fp_poly
			(pts
				(xy -0.9652 -1.778) (xy 0.9652 -1.778) (xy 0.9652 1.778) (xy -0.9652 1.778)
			)
			(stroke
				(width 0)
				(type default)
			)
			(fill no)
			(layer "F.Fab")
		)
		(pad "1" smd rect
			(at 0 -0.9652)
			(size 1.397 1.143)
			(layers "F.Cu" "F.Mask" "F.Paste")
			(net "P12V_HDD35")
		)
		(pad "2" smd rect
			(at 0 0.9652)
			(size 1.397 1.143)
			(layers "F.Cu" "F.Mask" "F.Paste")
			(net "GND")
		)
	)
	(footprint ""
		(layer "F.Cu")
		(at 35.260788 -253.3015 -90)
		(property "Reference" "R1210"
			(at 0 0 270)
			(layer "F.SilkS")
			(hide yes)
			(effects
				(font
					(size 1.27 1.27)
				)
			)
		)
		(property "Value" "10KR2F-2-GP"
			(at 0.064008 -3.993896 270)
			(unlocked yes)
			(layer "F.Fab")
			(hide yes)
			(effects
				(font
					(size 1.016 1.016)
					(thickness 0.1524)
				)
			)
		)
		(property "Device Type" "R402H16"
			(at 0.064008 -5.517896 270)
			(unlocked yes)
			(layer "F.Fab")
			(hide yes)
			(effects
				(font
					(size 1.016 1.016)
					(thickness 0.1524)
				)
			)
		)
		(duplicate_pad_numbers_are_jumpers no)
		(fp_line
			(start -0.508 -0.9398)
			(end -0.508 0.9398)
			(stroke
				(width 0.1524)
				(type default)
			)
			(layer "F.SilkS")
		)
		(fp_line
			(start 0.508 -0.9398)
			(end -0.508 -0.9398)
			(stroke
				(width 0.1524)
				(type default)
			)
			(layer "F.SilkS")
		)
		(fp_rect
			(start -0.508 0.9398)
			(end 0.508 -0.9398)
			(stroke
				(width 0)
				(type default)
			)
			(fill no)
			(layer "F.CrtYd")
		)
		(fp_rect
			(start -0.508 0.9398)
			(end 0.508 -0.9398)
			(stroke
				(width 0)
				(type default)
			)
			(fill no)
			(layer "F.Fab")
		)
		(pad "1" smd custom
			(at 0 -0.4445 270)
			(size 0.1397 0.1397)
			(layers "F.Cu" "F.Mask" "F.Paste")
			(net "P5V_A_1")
			(options
				(clearance outline)
				(anchor circle)
			)
			(primitives
				(gr_poly
					(pts
						(arc
							(start -0.1778 -0.2794)
							(mid -0.249642 -0.249642)
							(end -0.2794 -0.1778)
						)
						(arc
							(start -0.2794 0.1778)
							(mid -0.249642 0.249642)
							(end -0.1778 0.2794)
						)
						(arc
							(start 0.1778 0.2794)
							(mid 0.249642 0.249642)
							(end 0.2794 0.1778)
						)
						(arc
							(start 0.2794 -0.1778)
							(mid 0.249642 -0.249642)
							(end 0.1778 -0.2794)
						)
					)
					(width 0)
					(fill yes)
				)
			)
		)
		(pad "2" smd custom
			(at 0 0.4445 270)
			(size 0.1397 0.1397)
			(layers "F.Cu" "F.Mask" "F.Paste")
			(net "P5V_A_1_PGOOD")
			(options
				(clearance outline)
				(anchor circle)
			)
			(primitives
				(gr_poly
					(pts
						(arc
							(start -0.1778 -0.2794)
							(mid -0.249642 -0.249642)
							(end -0.2794 -0.1778)
						)
						(arc
							(start -0.2794 0.1778)
							(mid -0.249642 0.249642)
							(end -0.1778 0.2794)
						)
						(arc
							(start 0.1778 0.2794)
							(mid 0.249642 0.249642)
							(end 0.2794 0.1778)
						)
						(arc
							(start 0.2794 -0.1778)
							(mid 0.249642 -0.249642)
							(end 0.1778 -0.2794)
						)
					)
					(width 0)
					(fill yes)
				)
			)
		)
	)
	(footprint ""
		(layer "F.Cu")
		(at 359.681526 -134.075678 90)
		(property "Reference" "R1098"
			(at 0 0 90)
			(layer "F.SilkS")
			(hide yes)
			(effects
				(font
					(size 1.27 1.27)
				)
			)
		)
		(property "Value" "49K9R2F-L-GP"
			(at 0.064008 -3.993896 90)
			(unlocked yes)
			(layer "F.Fab")
			(hide yes)
			(effects
				(font
					(size 1.016 1.016)
					(thickness 0.1524)
				)
			)
		)
		(property "Device Type" "R402H16"
			(at 0.064008 -5.517896 90)
			(unlocked yes)
			(layer "F.Fab")
			(hide yes)
			(effects
				(font
					(size 1.016 1.016)
					(thickness 0.1524)
				)
			)
		)
		(duplicate_pad_numbers_are_jumpers no)
		(fp_line
			(start 0.508 -0.9398)
			(end -0.508 -0.9398)
			(stroke
				(width 0.1524)
				(type default)
			)
			(layer "F.SilkS")
		)
		(fp_line
			(start -0.508 -0.9398)
			(end -0.508 0.9398)
			(stroke
				(width 0.1524)
				(type default)
			)
			(layer "F.SilkS")
		)
		(fp_rect
			(start -0.508 0.9398)
			(end 0.508 -0.9398)
			(stroke
				(width 0)
				(type default)
			)
			(fill no)
			(layer "F.CrtYd")
		)
		(fp_rect
			(start -0.508 0.9398)
			(end 0.508 -0.9398)
			(stroke
				(width 0)
				(type default)
			)
			(fill no)
			(layer "F.Fab")
		)
		(pad "1" smd custom
			(at 0 -0.4445 90)
			(size 0.1397 0.1397)
			(layers "F.Cu" "F.Mask" "F.Paste")
			(net "P12V_B")
			(options
				(clearance outline)
				(anchor circle)
			)
			(primitives
				(gr_poly
					(pts
						(arc
							(start -0.1778 -0.2794)
							(mid -0.249642 -0.249642)
							(end -0.2794 -0.1778)
						)
						(arc
							(start -0.2794 0.1778)
							(mid -0.249642 0.249642)
							(end -0.1778 0.2794)
						)
						(arc
							(start 0.1778 0.2794)
							(mid 0.249642 0.249642)
							(end 0.2794 0.1778)
						)
						(arc
							(start 0.2794 -0.1778)
							(mid 0.249642 -0.249642)
							(end 0.1778 -0.2794)
						)
					)
					(width 0)
					(fill yes)
				)
			)
		)
		(pad "2" smd custom
			(at 0 0.4445 90)
			(size 0.1397 0.1397)
			(layers "F.Cu" "F.Mask" "F.Paste")
			(net "MB1_CM_UV_R")
			(options
				(clearance outline)
				(anchor circle)
			)
			(primitives
				(gr_poly
					(pts
						(arc
							(start -0.1778 -0.2794)
							(mid -0.249642 -0.249642)
							(end -0.2794 -0.1778)
						)
						(arc
							(start -0.2794 0.1778)
							(mid -0.249642 0.249642)
							(end -0.1778 0.2794)
						)
						(arc
							(start 0.1778 0.2794)
							(mid 0.249642 0.249642)
							(end 0.2794 0.1778)
						)
						(arc
							(start 0.2794 -0.1778)
							(mid 0.249642 -0.249642)
							(end 0.1778 -0.2794)
						)
					)
					(width 0)
					(fill yes)
				)
			)
		)
	)
)
